G04*
G04 #@! TF.GenerationSoftware,Altium Limited,Altium Designer,22.4.2 (48)*
G04*
G04 Layer_Color=0*
%FSLAX25Y25*%
%MOIN*%
G70*
G04*
G04 #@! TF.SameCoordinates,446674BB-F454-490D-8607-5140536C8ADF*
G04*
G04*
G04 #@! TF.FilePolarity,Positive*
G04*
G01*
G75*
M02*
